(kicad_pcb
	(version 20241229)
	(generator "pcbnew")
	(generator_version "9.0")
	(general
		(thickness 1.711)
		(legacy_teardrops no)
	)
	(paper "A4")
	(title_block
		(title "Antmicro Baseboard for Jetson AGX Thor")
		(date "2026-02-18")
		(rev "1.1.0")
		(company "Antmicro Ltd")
		(comment 1 "www.antmicro.com")
		(comment 9 "footprints 695-699 of 1170")
	)
	(layers
		(0 "F.Cu" signal)
		(4 "In1.Cu" signal)
		(6 "In2.Cu" signal)
		(8 "In3.Cu" signal)
		(10 "In4.Cu" jumper)
		(12 "In5.Cu" signal)
		(14 "In6.Cu" signal)
		(16 "In7.Cu" signal)
		(18 "In8.Cu" signal)
		(2 "B.Cu" signal)
		(9 "F.Adhes" user "F.Adhesive")
		(11 "B.Adhes" user "B.Adhesive")
		(13 "F.Paste" user)
		(15 "B.Paste" user)
		(5 "F.SilkS" user "F.Silkscreen")
		(7 "B.SilkS" user "B.Silkscreen")
		(1 "F.Mask" user)
		(3 "B.Mask" user)
		(17 "Dwgs.User" user "User.Drawings")
		(19 "Cmts.User" user "User.Comments")
		(21 "Eco1.User" user "User.Eco1")
		(23 "Eco2.User" user "User.Eco2")
		(25 "Edge.Cuts" user)
		(27 "Margin" user)
		(31 "F.CrtYd" user "F.Courtyard")
		(29 "B.CrtYd" user "B.Courtyard")
		(35 "F.Fab" user)
		(33 "B.Fab" user)
	)
	(footprint "antmicro-footprints:TP_SMD_0.75mm"
		(layer "B.Cu")
		(at 169.64 58 180)
		(property "Reference" "TP133"
			(at -0.43 4.05 90)
			(layer "B.SilkS")
			(effects
				(font
					(size 0.7 0.7)
					(thickness 0.15)
				)
				(justify left bottom mirror)
			)
		)
		(property "Value" "TP_0.75mm_SMD"
			(at 0 -1.2 0)
			(layer "B.Fab")
			(effects
				(font
					(size 0.7 0.7)
					(thickness 0.15)
				)
				(justify left bottom mirror)
			)
		)
		(property "Description" "SMT test point"
			(at 0 0 0)
			(layer "B.Fab")
			(hide yes)
			(effects
				(font
					(size 1.27 1.27)
					(thickness 0.15)
				)
				(justify mirror)
			)
		)
		(property "MPN" ""
			(at 0 0 0)
			(unlocked yes)
			(layer "B.Fab")
			(hide yes)
			(effects
				(font
					(size 1 1)
					(thickness 0.15)
				)
				(justify mirror)
			)
		)
		(property "Manufacturer" ""
			(at 0 0 0)
			(unlocked yes)
			(layer "B.Fab")
			(hide yes)
			(effects
				(font
					(size 1 1)
					(thickness 0.15)
				)
				(justify mirror)
			)
		)
		(property "Author" "Antmicro"
			(at 0 0 0)
			(unlocked yes)
			(layer "B.Fab")
			(hide yes)
			(effects
				(font
					(size 1 1)
					(thickness 0.15)
				)
				(justify mirror)
			)
		)
		(property "License" "Apache-2.0"
			(at 0 0 0)
			(unlocked yes)
			(layer "B.Fab")
			(hide yes)
			(effects
				(font
					(size 1 1)
					(thickness 0.15)
				)
				(justify mirror)
			)
		)
		(sheetname "/Power/")
		(sheetfile "power.kicad_sch")
		(attr exclude_from_pos_files exclude_from_bom)
		(fp_circle
			(center 0 0)
			(end 0.475 0)
			(stroke
				(width 0.05)
				(type default)
			)
			(fill no)
			(layer "B.CrtYd")
		)
		(fp_text user "${REFERENCE}"
			(at -0.4 -2.7 0)
			(layer "B.Fab")
			(effects
				(font
					(size 0.7 0.7)
					(thickness 0.15)
				)
				(justify left bottom mirror)
			)
		)
		(fp_text user "License: Apache-2.0"
			(at -0.4 -5.101 0)
			(layer "B.Fab")
			(effects
				(font
					(size 0.7 0.7)
					(thickness 0.15)
				)
				(justify left bottom mirror)
			)
		)
		(fp_text user "Author: Antmicro"
			(at -0.4 -3.901 0)
			(layer "B.Fab")
			(effects
				(font
					(size 0.7 0.7)
					(thickness 0.15)
				)
				(justify left bottom mirror)
			)
		)
		(pad "1" smd circle
			(at 0 0 180)
			(size 0.75 0.75)
			(layers "B.Cu" "B.Mask")
			(net 4 "+3V3_AON")
			(pinfunction "1")
			(pintype "passive")
		)
	)
	(footprint "antmicro-footprints:TP_SMD_0.75mm"
		(layer "B.Cu")
		(at 193.28 80.6815)
		(property "Reference" "TP15"
			(at 0.52 -3.2315 90)
			(layer "B.SilkS")
			(effects
				(font
					(size 0.7 0.7)
					(thickness 0.15)
				)
				(justify left bottom mirror)
			)
		)
		(property "Value" "TP_0.75mm_SMD"
			(at 0 -1.2 180)
			(layer "B.Fab")
			(effects
				(font
					(size 0.7 0.7)
					(thickness 0.15)
				)
				(justify left bottom mirror)
			)
		)
		(property "Description" "SMT test point"
			(at 0 0 180)
			(layer "B.Fab")
			(hide yes)
			(effects
				(font
					(size 1.27 1.27)
					(thickness 0.15)
				)
				(justify mirror)
			)
		)
		(property "MPN" ""
			(at 0 0 180)
			(unlocked yes)
			(layer "B.Fab")
			(hide yes)
			(effects
				(font
					(size 1 1)
					(thickness 0.15)
				)
				(justify mirror)
			)
		)
		(property "Manufacturer" ""
			(at 0 0 180)
			(unlocked yes)
			(layer "B.Fab")
			(hide yes)
			(effects
				(font
					(size 1 1)
					(thickness 0.15)
				)
				(justify mirror)
			)
		)
		(property "Author" "Antmicro"
			(at 0 0 180)
			(unlocked yes)
			(layer "B.Fab")
			(hide yes)
			(effects
				(font
					(size 1 1)
					(thickness 0.15)
				)
				(justify mirror)
			)
		)
		(property "License" "Apache-2.0"
			(at 0 0 180)
			(unlocked yes)
			(layer "B.Fab")
			(hide yes)
			(effects
				(font
					(size 1 1)
					(thickness 0.15)
				)
				(justify mirror)
			)
		)
		(sheetname "/USB Debug, PD/")
		(sheetfile "usb_debug_pd.kicad_sch")
		(attr exclude_from_pos_files exclude_from_bom)
		(fp_circle
			(center 0 0)
			(end 0.475 0)
			(stroke
				(width 0.05)
				(type default)
			)
			(fill no)
			(layer "B.CrtYd")
		)
		(fp_text user "License: Apache-2.0"
			(at -0.4 -5.101 180)
			(layer "B.Fab")
			(effects
				(font
					(size 0.7 0.7)
					(thickness 0.15)
				)
				(justify left bottom mirror)
			)
		)
		(fp_text user "Author: Antmicro"
			(at -0.4 -3.901 180)
			(layer "B.Fab")
			(effects
				(font
					(size 0.7 0.7)
					(thickness 0.15)
				)
				(justify left bottom mirror)
			)
		)
		(fp_text user "${REFERENCE}"
			(at -0.4 -2.7 180)
			(layer "B.Fab")
			(effects
				(font
					(size 0.7 0.7)
					(thickness 0.15)
				)
				(justify left bottom mirror)
			)
		)
		(pad "1" smd circle
			(at 0 0)
			(size 0.75 0.75)
			(layers "B.Cu" "B.Mask")
			(net 950 "/USB Debug, PD/PDC_I2C2_SDA")
			(pinfunction "1")
			(pintype "passive")
		)
	)
	(footprint "antmicro-footprints:R_0402_1005Metric"
		(layer "B.Cu")
		(at 213.789 81.225 180)
		(descr "Resistor SMD 0402")
		(tags "resistor SMD 0402")
		(property "Reference" "R114"
			(at 0.189 -2.375 0)
			(layer "B.SilkS")
			(effects
				(font
					(size 0.7 0.7)
					(thickness 0.15)
				)
				(justify left bottom mirror)
			)
		)
		(property "Value" "R_1k_0402"
			(at -1.011843 -1.772046 0)
			(layer "B.Fab")
			(effects
				(font
					(size 0.7 0.7)
					(thickness 0.15)
				)
				(justify left bottom mirror)
			)
		)
		(property "Datasheet" "https://www.bourns.com/docs/product-datasheets/cr.pdf"
			(at 0 0 0)
			(layer "B.Fab")
			(hide yes)
			(effects
				(font
					(size 1.27 1.27)
					(thickness 0.15)
				)
				(justify mirror)
			)
		)
		(property "Description" "SMD Chip Resistor, 1 kohm, ± 1%, 63 mW, 0402 [1005 Metric], Thick Film, General Purpose"
			(at 0 0 0)
			(layer "B.Fab")
			(hide yes)
			(effects
				(font
					(size 1.27 1.27)
					(thickness 0.15)
				)
				(justify mirror)
			)
		)
		(property "MPN" "CR0402-FX-1001GLF"
			(at 0 0 0)
			(unlocked yes)
			(layer "B.Fab")
			(hide yes)
			(effects
				(font
					(size 1 1)
					(thickness 0.15)
				)
				(justify mirror)
			)
		)
		(property "Manufacturer" "Bourns"
			(at 0 0 0)
			(unlocked yes)
			(layer "B.Fab")
			(hide yes)
			(effects
				(font
					(size 1 1)
					(thickness 0.15)
				)
				(justify mirror)
			)
		)
		(property "License" "Apache-2.0"
			(at 0 0 0)
			(unlocked yes)
			(layer "B.Fab")
			(hide yes)
			(effects
				(font
					(size 1 1)
					(thickness 0.15)
				)
				(justify mirror)
			)
		)
		(property "Author" "Antmicro"
			(at 0 0 0)
			(unlocked yes)
			(layer "B.Fab")
			(hide yes)
			(effects
				(font
					(size 1 1)
					(thickness 0.15)
				)
				(justify mirror)
			)
		)
		(property "Val" "1k"
			(at 0 0 0)
			(unlocked yes)
			(layer "B.Fab")
			(hide yes)
			(effects
				(font
					(size 1 1)
					(thickness 0.15)
				)
				(justify mirror)
			)
		)
		(property "Tolerance" "1%"
			(at 0 0 0)
			(unlocked yes)
			(layer "B.Fab")
			(hide yes)
			(effects
				(font
					(size 1 1)
					(thickness 0.15)
				)
				(justify mirror)
			)
		)
		(sheetname "/USB Debug, PD/")
		(sheetfile "usb_debug_pd.kicad_sch")
		(attr smd)
		(fp_poly
			(pts
				(xy -0.925 0.47) (xy -0.925 -0.47) (xy 0.925 -0.47) (xy 0.925 0.47)
			)
			(stroke
				(width 0.05)
				(type default)
			)
			(fill no)
			(layer "B.CrtYd")
		)
		(fp_poly
			(pts
				(xy -0.5 0.25) (xy -0.5 -0.25) (xy 0.5 -0.25) (xy 0.5 0.25)
			)
			(stroke
				(width 0.15)
				(type solid)
			)
			(fill no)
			(layer "B.Fab")
		)
		(fp_text user "${REFERENCE}"
			(at -0.95 -3.168 0)
			(layer "B.Fab")
			(effects
				(font
					(size 0.7 0.7)
					(thickness 0.15)
				)
				(justify left bottom mirror)
			)
		)
		(fp_text user "License: Apache-2.0"
			(at -0.949999 -5.169 0)
			(layer "B.Fab")
			(effects
				(font
					(size 0.7 0.7)
					(thickness 0.15)
				)
				(justify left bottom mirror)
			)
		)
		(fp_text user "Author: Antmicro"
			(at -0.95 -4.169 0)
			(layer "B.Fab")
			(effects
				(font
					(size 0.7 0.7)
					(thickness 0.15)
				)
				(justify left bottom mirror)
			)
		)
		(pad "1" smd roundrect
			(at -0.48 0 180)
			(size 0.59 0.64)
			(layers "B.Cu" "B.Mask" "B.Paste")
			(roundrect_rratio 0.25)
			(net 956 "/USB Debug, PD/FTDI_CBUS0{slash}SDA")
			(pintype "passive")
		)
		(pad "2" smd roundrect
			(at 0.48 0 180)
			(size 0.59 0.64)
			(layers "B.Cu" "B.Mask" "B.Paste")
			(roundrect_rratio 0.25)
			(net 334 "/USB Debug, PD/FTDI_3V3")
			(pintype "passive")
		)
	)
	(footprint "antmicro-footprints:R_0402_1005Metric"
		(layer "B.Cu")
		(at 223.56 124.4)
		(descr "Resistor SMD 0402")
		(tags "resistor SMD 0402")
		(property "Reference" "R336"
			(at 0.94 -0.6 0)
			(layer "B.SilkS")
			(effects
				(font
					(size 0.7 0.7)
					(thickness 0.15)
				)
				(justify right top mirror)
			)
		)
		(property "Value" "R_2R2_0402"
			(at -1.011843 -1.772047 0)
			(layer "B.Fab")
			(effects
				(font
					(size 0.7 0.7)
					(thickness 0.15)
				)
				(justify right top mirror)
			)
		)
		(property "Datasheet" "https://www.bourns.com/docs/product-datasheets/cr.pdf"
			(at 0 0 0)
			(layer "B.Fab")
			(hide yes)
			(effects
				(font
					(size 1.27 1.27)
					(thickness 0.15)
				)
				(justify mirror)
			)
		)
		(property "Description" "SMD Chip Resistor, 2.2 ohm, ± 1%, 62.5 mW, 0402 [1005 Metric], Thick Film, General Purpose"
			(at 0 0 0)
			(layer "B.Fab")
			(hide yes)
			(effects
				(font
					(size 1.27 1.27)
					(thickness 0.15)
				)
				(justify mirror)
			)
		)
		(property "MPN" "CR0402-FX-2R20GLF"
			(at 0 0 180)
			(unlocked yes)
			(layer "B.Fab")
			(hide yes)
			(effects
				(font
					(size 1 1)
					(thickness 0.15)
				)
				(justify mirror)
			)
		)
		(property "Manufacturer" "Bourns"
			(at 0 0 180)
			(unlocked yes)
			(layer "B.Fab")
			(hide yes)
			(effects
				(font
					(size 1 1)
					(thickness 0.15)
				)
				(justify mirror)
			)
		)
		(property "License" "Apache-2.0"
			(at 0 0 180)
			(unlocked yes)
			(layer "B.Fab")
			(hide yes)
			(effects
				(font
					(size 1 1)
					(thickness 0.15)
				)
				(justify mirror)
			)
		)
		(property "Author" "Antmicro"
			(at 0 0 180)
			(unlocked yes)
			(layer "B.Fab")
			(hide yes)
			(effects
				(font
					(size 1 1)
					(thickness 0.15)
				)
				(justify mirror)
			)
		)
		(property "Val" "2R2"
			(at 0 0 180)
			(unlocked yes)
			(layer "B.Fab")
			(hide yes)
			(effects
				(font
					(size 1 1)
					(thickness 0.15)
				)
				(justify mirror)
			)
		)
		(property "Tolerance" "1%"
			(at 0 0 180)
			(unlocked yes)
			(layer "B.Fab")
			(hide yes)
			(effects
				(font
					(size 1 1)
					(thickness 0.15)
				)
				(justify mirror)
			)
		)
		(sheetname "/USB Hub/")
		(sheetfile "usb_hub.kicad_sch")
		(attr smd)
		(fp_rect
			(start -0.925 0.47)
			(end 0.925 -0.47)
			(stroke
				(width 0.05)
				(type default)
			)
			(fill no)
			(layer "B.CrtYd")
		)
		(fp_rect
			(start -0.5 0.25)
			(end 0.5 -0.25)
			(stroke
				(width 0.15)
				(type solid)
			)
			(fill no)
			(layer "B.Fab")
		)
		(fp_text user "License: Apache-2.0"
			(at -0.95 -5.169 0)
			(layer "B.Fab")
			(effects
				(font
					(size 0.7 0.7)
					(thickness 0.15)
				)
				(justify right top mirror)
			)
		)
		(fp_text user "${REFERENCE}"
			(at -0.95 -3.168 0)
			(layer "B.Fab")
			(effects
				(font
					(size 0.7 0.7)
					(thickness 0.15)
				)
				(justify right top mirror)
			)
		)
		(fp_text user "Author: Antmicro"
			(at -0.95 -4.169 0)
			(layer "B.Fab")
			(effects
				(font
					(size 0.7 0.7)
					(thickness 0.15)
				)
				(justify right top mirror)
			)
		)
		(pad "1" smd roundrect
			(at -0.48 0)
			(size 0.59 0.64)
			(layers "B.Cu" "B.Mask" "B.Paste")
			(roundrect_rratio 0.25)
			(net 1238 "Net-(D59-C)")
			(pintype "passive")
		)
		(pad "2" smd roundrect
			(at 0.48 0)
			(size 0.59 0.64)
			(layers "B.Cu" "B.Mask" "B.Paste")
			(roundrect_rratio 0.25)
			(net 503 "/USB Hub/USBC4_CC_{1}")
			(pintype "passive")
		)
	)
	(footprint "antmicro-footprints:R_0402_1005Metric"
		(layer "B.Cu")
		(at 207 62.483)
		(descr "Resistor SMD 0402")
		(tags "resistor SMD 0402")
		(property "Reference" "R180"
			(at -3.77 -0.48 0)
			(layer "B.SilkS")
			(effects
				(font
					(size 0.7 0.7)
					(thickness 0.15)
				)
				(justify right top mirror)
			)
		)
		(property "Value" "R_4k7_0402"
			(at -1.011843 -1.772046 0)
			(layer "B.Fab")
			(effects
				(font
					(size 0.7 0.7)
					(thickness 0.15)
				)
				(justify right top mirror)
			)
		)
		(property "Datasheet" "https://www.bourns.com/docs/product-datasheets/cr.pdf"
			(at 0 0 0)
			(layer "B.Fab")
			(hide yes)
			(effects
				(font
					(size 1.27 1.27)
					(thickness 0.15)
				)
				(justify mirror)
			)
		)
		(property "Description" "SMD Chip Resistor, 4.7 kohm, ± 1%, 62.5 mW, 0402 [1005 Metric], Thick Film, General Purpose"
			(at 0 0 0)
			(layer "B.Fab")
			(hide yes)
			(effects
				(font
					(size 1.27 1.27)
					(thickness 0.15)
				)
				(justify mirror)
			)
		)
		(property "Manufacturer" "Bourns"
			(at 0 0 180)
			(unlocked yes)
			(layer "B.Fab")
			(hide yes)
			(effects
				(font
					(size 1 1)
					(thickness 0.15)
				)
				(justify mirror)
			)
		)
		(property "MPN" "CR0402-FX-4701GLF"
			(at 0 0 180)
			(unlocked yes)
			(layer "B.Fab")
			(hide yes)
			(effects
				(font
					(size 1 1)
					(thickness 0.15)
				)
				(justify mirror)
			)
		)
		(property "Val" "4k7"
			(at 0 0 180)
			(unlocked yes)
			(layer "B.Fab")
			(hide yes)
			(effects
				(font
					(size 1 1)
					(thickness 0.15)
				)
				(justify mirror)
			)
		)
		(property "License" "Apache-2.0"
			(at 0 0 180)
			(unlocked yes)
			(layer "B.Fab")
			(hide yes)
			(effects
				(font
					(size 1 1)
					(thickness 0.15)
				)
				(justify mirror)
			)
		)
		(property "Author" "Antmicro"
			(at 0 0 180)
			(unlocked yes)
			(layer "B.Fab")
			(hide yes)
			(effects
				(font
					(size 1 1)
					(thickness 0.15)
				)
				(justify mirror)
			)
		)
		(property "Tolerance" "1%"
			(at 0 0 180)
			(unlocked yes)
			(layer "B.Fab")
			(hide yes)
			(effects
				(font
					(size 1 1)
					(thickness 0.15)
				)
				(justify mirror)
			)
		)
		(sheetname "/CSI/")
		(sheetfile "csi.kicad_sch")
		(attr smd)
		(fp_poly
			(pts
				(xy -0.925 0.47) (xy -0.925 -0.47) (xy 0.925 -0.47) (xy 0.925 0.47)
			)
			(stroke
				(width 0.05)
				(type default)
			)
			(fill no)
			(layer "B.CrtYd")
		)
		(fp_poly
			(pts
				(xy -0.5 0.25) (xy -0.5 -0.25) (xy 0.5 -0.25) (xy 0.5 0.25)
			)
			(stroke
				(width 0.15)
				(type solid)
			)
			(fill no)
			(layer "B.Fab")
		)
		(fp_text user "License: Apache-2.0"
			(at -0.949999 -5.169 0)
			(layer "B.Fab")
			(effects
				(font
					(size 0.7 0.7)
					(thickness 0.15)
				)
				(justify right top mirror)
			)
		)
		(fp_text user "${REFERENCE}"
			(at -0.95 -3.168 0)
			(layer "B.Fab")
			(effects
				(font
					(size 0.7 0.7)
					(thickness 0.15)
				)
				(justify right top mirror)
			)
		)
		(fp_text user "Author: Antmicro"
			(at -0.95 -4.169 0)
			(layer "B.Fab")
			(effects
				(font
					(size 0.7 0.7)
					(thickness 0.15)
				)
				(justify right top mirror)
			)
		)
		(pad "1" smd roundrect
			(at -0.48 0)
			(size 0.59 0.64)
			(layers "B.Cu" "B.Mask" "B.Paste")
			(roundrect_rratio 0.25)
			(net 1 "GND")
			(pintype "passive")
		)
		(pad "2" smd roundrect
			(at 0.48 0)
			(size 0.59 0.64)
			(layers "B.Cu" "B.Mask" "B.Paste")
			(roundrect_rratio 0.25)
			(net 998 "/CSI/CSIB_3V3_ISET")
			(pintype "passive")
		)
	)
)
